# SCM (Grand Teton) — schematic netlist excerpt (pin names and nets, part order shuffled) for the footprints in the layout excerpt that follows; sources: Cadence DE-HDL packaged netlist, KiCad conversion of 12092022_DA0F0TMDCD0_F0T_Management_Board_D_brd_V3_OCP.brd

R736  Q_RES  1K 1% CHIP  pkg 0402LF  page 28 : A = P3V3_AUX ; B = FM_SOL_UART_CH_SEL_R3
R242  Q_RES  33.2 1% CHIP  pkg 0402LF  page 13 : A = FM_BMC_CPU_FBRK_OUT_N ; B = FM_BMC_CPU_FBRK_OUT_R_N

(kicad_pcb
	(version 20260206)
	(generator "pcbnew")
	(generator_version "10.0")
	(general
		(thickness 1.6)
		(legacy_teardrops no)
	)
	(paper "A4")
	(title_block
		(title "12092022_DA0F0TMDCD0_F0T_Management_Board_D_brd_V3_OCP.brd")
		(comment 1 "Grand Teton / footprints 925-927 of 1440")
	)
	(layers
		(0 "F.Cu" signal "TOP")
		(4 "In1.Cu" signal "GND")
		(6 "In2.Cu" signal "IN1")
		(8 "In3.Cu" signal "GND1")
		(10 "In4.Cu" signal "IN2")
		(12 "In5.Cu" signal "VCC")
		(14 "In6.Cu" signal "VCC1")
		(16 "In7.Cu" signal "IN3")
		(18 "In8.Cu" signal "GND2")
		(20 "In9.Cu" signal "IN4")
		(22 "In10.Cu" signal "GND3")
		(2 "B.Cu" signal "BOTTOM")
		(9 "F.Adhes" user "F.Adhesive")
		(11 "B.Adhes" user "B.Adhesive")
		(13 "F.Paste" user "Package Geometry/Pastemask Top")
		(15 "B.Paste" user "Package Geometry/Pastemask Bottom")
		(5 "F.SilkS" user "Ref Des/Silkscreen Top")
		(7 "B.SilkS" user "Ref Des/Silkscreen Bottom")
		(1 "F.Mask" user "Board Geometry/Soldermask Top")
		(3 "B.Mask" user "Board Geometry/Soldermask Bottom")
		(17 "Dwgs.User" user "User.Drawings")
		(19 "Cmts.User" user "User.Comments")
		(21 "Eco1.User" user "User.Eco1")
		(23 "Eco2.User" user "User.Eco2")
		(25 "Edge.Cuts" user "Board Geometry/Outline")
		(27 "Margin" user)
		(31 "F.CrtYd" user "Package Geometry/Place Bound Top")
		(29 "B.CrtYd" user "Package Geometry/Place Bound Bottom")
		(35 "F.Fab" user "Ref Des/Assembly Top")
		(33 "B.Fab" user "Ref Des/Assembly Bottom")
	)
	(footprint ""
		(layer "B.Cu")
		(at 42.22115 -38.9636 180)
		(property "Reference" "R242"
			(at 0 0 0)
			(layer "B.SilkS")
			(hide yes)
			(effects
				(font
					(size 1.27 1.27)
				)
				(justify mirror)
			)
		)
		(property "Value" ""
			(at 0 0 0)
			(layer "B.Fab")
			(effects
				(font
					(size 1.27 1.27)
				)
				(justify mirror)
			)
		)
		(duplicate_pad_numbers_are_jumpers no)
		(fp_line
			(start 0.7874 0.4064)
			(end 0.7874 -0.4064)
			(stroke
				(width 0.1524)
				(type default)
			)
			(layer "B.SilkS")
		)
		(fp_line
			(start 0.7874 -0.4064)
			(end -0.7874 -0.4064)
			(stroke
				(width 0.1524)
				(type default)
			)
			(layer "B.SilkS")
		)
		(fp_line
			(start -0.7874 0.4064)
			(end 0.7874 0.4064)
			(stroke
				(width 0.1524)
				(type default)
			)
			(layer "B.SilkS")
		)
		(fp_line
			(start -0.7874 -0.4064)
			(end -0.7874 0.4064)
			(stroke
				(width 0.1524)
				(type default)
			)
			(layer "B.SilkS")
		)
		(fp_line
			(start 0.67945 0.3048)
			(end 0.67945 -0.305054)
			(stroke
				(width 0.1)
				(type default)
			)
			(layer "B.Fab")
		)
		(fp_line
			(start 0.67945 -0.305054)
			(end 0.12065 -0.305054)
			(stroke
				(width 0.1)
				(type default)
			)
			(layer "B.Fab")
		)
		(fp_line
			(start 0.12065 0.3048)
			(end 0.67945 0.3048)
			(stroke
				(width 0.1)
				(type default)
			)
			(layer "B.Fab")
		)
		(fp_line
			(start 0.12065 0.2794)
			(end 0.12065 0.3048)
			(stroke
				(width 0.1)
				(type default)
			)
			(layer "B.Fab")
		)
		(fp_line
			(start 0.12065 -0.2794)
			(end -0.12065 -0.2794)
			(stroke
				(width 0.1)
				(type default)
			)
			(layer "B.Fab")
		)
		(fp_line
			(start 0.12065 -0.305054)
			(end 0.12065 -0.2794)
			(stroke
				(width 0.1)
				(type default)
			)
			(layer "B.Fab")
		)
		(fp_line
			(start -0.120396 0.3048)
			(end -0.120396 0.2794)
			(stroke
				(width 0.1)
				(type default)
			)
			(layer "B.Fab")
		)
		(fp_line
			(start -0.120396 0.2794)
			(end 0.12065 0.2794)
			(stroke
				(width 0.1)
				(type default)
			)
			(layer "B.Fab")
		)
		(fp_line
			(start -0.12065 -0.2794)
			(end -0.12065 -0.3048)
			(stroke
				(width 0.1)
				(type default)
			)
			(layer "B.Fab")
		)
		(fp_line
			(start -0.12065 -0.3048)
			(end -0.67945 -0.3048)
			(stroke
				(width 0.1)
				(type default)
			)
			(layer "B.Fab")
		)
		(fp_line
			(start -0.67945 0.3048)
			(end -0.120396 0.3048)
			(stroke
				(width 0.1)
				(type default)
			)
			(layer "B.Fab")
		)
		(fp_line
			(start -0.67945 -0.3048)
			(end -0.67945 0.3048)
			(stroke
				(width 0.1)
				(type default)
			)
			(layer "B.Fab")
		)
		(pad "1" smd circle
			(at 0.40005 0)
			(size 0 0)
			(layers "B.Cu" "B.Mask" "B.Paste")
			(net "FM_BMC_CPU_FBRK_OUT_N")
		)
		(pad "2" smd circle
			(at -0.40005 0)
			(size 0 0)
			(layers "B.Cu" "B.Mask" "B.Paste")
			(net "FM_BMC_CPU_FBRK_OUT_R_N")
		)
	)
	(footprint ""
		(layer "B.Cu")
		(at 52.2986 -25.273)
		(property "Reference" ""
			(at 0 0 0)
			(layer "B.SilkS")
			(hide yes)
			(effects
				(font
					(size 1.27 1.27)
				)
				(justify mirror)
			)
		)
		(property "Value" ""
			(at 0 0 0)
			(layer "B.Fab")
			(effects
				(font
					(size 1.27 1.27)
				)
				(justify mirror)
			)
		)
		(duplicate_pad_numbers_are_jumpers no)
		(pad "1" smd circle
			(at 0 0 180)
			(size 0.9906 0.9906)
			(layers "B.Cu" "B.Mask" "B.Paste")
			(net "Net_159")
		)
		(zone
			(layer "B.Cu")
			(hatch none 0.5)
			(connect_pads
				(clearance 0)
			)
			(min_thickness 0.25)
			(keepout
				(tracks not_allowed)
				(vias allowed)
				(pads allowed)
				(copperpour not_allowed)
				(footprints allowed)
			)
			(placement
				(enabled no)
				(sheetname "")
			)
			(fill
				(thermal_gap 0.5)
				(thermal_bridge_width 0.5)
				(island_removal_mode 0)
			)
			(polygon
				(pts
					(arc
						(start 53.9242 -25.273)
						(mid 50.673 -25.273)
						(end 53.9242 -25.273)
					)
				)
			)
		)
	)
	(footprint ""
		(layer "B.Cu")
		(at 61.7855 -100.1395 90)
		(property "Reference" "R736"
			(at 0 0 90)
			(layer "B.SilkS")
			(hide yes)
			(effects
				(font
					(size 1.27 1.27)
				)
				(justify mirror)
			)
		)
		(property "Value" ""
			(at 0 0 90)
			(layer "B.Fab")
			(effects
				(font
					(size 1.27 1.27)
				)
				(justify mirror)
			)
		)
		(duplicate_pad_numbers_are_jumpers no)
		(fp_line
			(start 0.7874 -0.4064)
			(end -0.7874 -0.4064)
			(stroke
				(width 0.1524)
				(type default)
			)
			(layer "B.SilkS")
		)
		(fp_line
			(start -0.7874 -0.4064)
			(end -0.7874 0.4064)
			(stroke
				(width 0.1524)
				(type default)
			)
			(layer "B.SilkS")
		)
		(fp_line
			(start 0.7874 0.4064)
			(end 0.7874 -0.4064)
			(stroke
				(width 0.1524)
				(type default)
			)
			(layer "B.SilkS")
		)
		(fp_line
			(start -0.7874 0.4064)
			(end 0.7874 0.4064)
			(stroke
				(width 0.1524)
				(type default)
			)
			(layer "B.SilkS")
		)
		(fp_line
			(start 0.67945 -0.305054)
			(end 0.12065 -0.305054)
			(stroke
				(width 0.1)
				(type default)
			)
			(layer "B.Fab")
		)
		(fp_line
			(start 0.12065 -0.305054)
			(end 0.12065 -0.2794)
			(stroke
				(width 0.1)
				(type default)
			)
			(layer "B.Fab")
		)
		(fp_line
			(start -0.12065 -0.3048)
			(end -0.67945 -0.3048)
			(stroke
				(width 0.1)
				(type default)
			)
			(layer "B.Fab")
		)
		(fp_line
			(start -0.67945 -0.3048)
			(end -0.67945 0.3048)
			(stroke
				(width 0.1)
				(type default)
			)
			(layer "B.Fab")
		)
		(fp_line
			(start 0.12065 -0.2794)
			(end -0.12065 -0.2794)
			(stroke
				(width 0.1)
				(type default)
			)
			(layer "B.Fab")
		)
		(fp_line
			(start -0.12065 -0.2794)
			(end -0.12065 -0.3048)
			(stroke
				(width 0.1)
				(type default)
			)
			(layer "B.Fab")
		)
		(fp_line
			(start 0.12065 0.2794)
			(end 0.12065 0.3048)
			(stroke
				(width 0.1)
				(type default)
			)
			(layer "B.Fab")
		)
		(fp_line
			(start -0.120396 0.2794)
			(end 0.12065 0.2794)
			(stroke
				(width 0.1)
				(type default)
			)
			(layer "B.Fab")
		)
		(fp_line
			(start 0.67945 0.3048)
			(end 0.67945 -0.305054)
			(stroke
				(width 0.1)
				(type default)
			)
			(layer "B.Fab")
		)
		(fp_line
			(start 0.12065 0.3048)
			(end 0.67945 0.3048)
			(stroke
				(width 0.1)
				(type default)
			)
			(layer "B.Fab")
		)
		(fp_line
			(start -0.120396 0.3048)
			(end -0.120396 0.2794)
			(stroke
				(width 0.1)
				(type default)
			)
			(layer "B.Fab")
		)
		(fp_line
			(start -0.67945 0.3048)
			(end -0.120396 0.3048)
			(stroke
				(width 0.1)
				(type default)
			)
			(layer "B.Fab")
		)
		(pad "1" smd circle
			(at 0.40005 0 270)
			(size 0 0)
			(layers "B.Cu" "B.Mask" "B.Paste")
			(net "P3V3_AUX")
		)
		(pad "2" smd circle
			(at -0.40005 0 270)
			(size 0 0)
			(layers "B.Cu" "B.Mask" "B.Paste")
			(net "FM_SOL_UART_CH_SEL_R3")
		)
	)
)
